(kicad_pcb
	(version 20241229)
	(generator "pcbnew")
	(generator_version "9.0")
	(general
		(thickness 1.711)
		(legacy_teardrops no)
	)
	(paper "A4")
	(title_block
		(title "Antmicro Baseboard for Jetson AGX Thor")
		(date "2026-02-18")
		(rev "1.1.0")
		(company "Antmicro Ltd")
		(comment 1 "www.antmicro.com")
		(comment 9 "footprints 828-832 of 1170")
	)
	(layers
		(0 "F.Cu" signal)
		(4 "In1.Cu" signal)
		(6 "In2.Cu" signal)
		(8 "In3.Cu" signal)
		(10 "In4.Cu" jumper)
		(12 "In5.Cu" signal)
		(14 "In6.Cu" signal)
		(16 "In7.Cu" signal)
		(18 "In8.Cu" signal)
		(2 "B.Cu" signal)
		(9 "F.Adhes" user "F.Adhesive")
		(11 "B.Adhes" user "B.Adhesive")
		(13 "F.Paste" user)
		(15 "B.Paste" user)
		(5 "F.SilkS" user "F.Silkscreen")
		(7 "B.SilkS" user "B.Silkscreen")
		(1 "F.Mask" user)
		(3 "B.Mask" user)
		(17 "Dwgs.User" user "User.Drawings")
		(19 "Cmts.User" user "User.Comments")
		(21 "Eco1.User" user "User.Eco1")
		(23 "Eco2.User" user "User.Eco2")
		(25 "Edge.Cuts" user)
		(27 "Margin" user)
		(31 "F.CrtYd" user "F.Courtyard")
		(29 "B.CrtYd" user "B.Courtyard")
		(35 "F.Fab" user)
		(33 "B.Fab" user)
	)
	(footprint "antmicro-footprints:R_0402_1005Metric"
		(layer "B.Cu")
		(at 223.85 95.868)
		(descr "Resistor SMD 0402")
		(tags "resistor SMD 0402")
		(property "Reference" "R155"
			(at -1.45 1.555 0)
			(layer "B.SilkS")
			(effects
				(font
					(size 0.7 0.7)
					(thickness 0.15)
				)
				(justify right top mirror)
			)
		)
		(property "Value" "R_2M_0402"
			(at -1.011843 -1.772047 0)
			(layer "B.Fab")
			(effects
				(font
					(size 0.7 0.7)
					(thickness 0.15)
				)
				(justify right top mirror)
			)
		)
		(property "Datasheet" "https://www.mouser.com/datasheet/2/447/YAGEO_PYu_RC_Group_51_RoHS_L_12-3313492.pdf"
			(at 0 0 0)
			(layer "B.Fab")
			(hide yes)
			(effects
				(font
					(size 1.27 1.27)
					(thickness 0.15)
				)
				(justify mirror)
			)
		)
		(property "Description" "SMD Chip Resistor, 2 Mohm, ± 1%, 62.5 mW, 0402 [1005 Metric], Thick Film, General Purpose"
			(at 0 0 0)
			(layer "B.Fab")
			(hide yes)
			(effects
				(font
					(size 1.27 1.27)
					(thickness 0.15)
				)
				(justify mirror)
			)
		)
		(property "MPN" "RC0402FR-072ML"
			(at 0 0 180)
			(unlocked yes)
			(layer "B.Fab")
			(hide yes)
			(effects
				(font
					(size 1 1)
					(thickness 0.15)
				)
				(justify mirror)
			)
		)
		(property "Manufacturer" "YAGEO"
			(at 0 0 180)
			(unlocked yes)
			(layer "B.Fab")
			(hide yes)
			(effects
				(font
					(size 1 1)
					(thickness 0.15)
				)
				(justify mirror)
			)
		)
		(property "License" "Apache-2.0"
			(at 0 0 180)
			(unlocked yes)
			(layer "B.Fab")
			(hide yes)
			(effects
				(font
					(size 1 1)
					(thickness 0.15)
				)
				(justify mirror)
			)
		)
		(property "Author" "Antmicro"
			(at 0 0 180)
			(unlocked yes)
			(layer "B.Fab")
			(hide yes)
			(effects
				(font
					(size 1 1)
					(thickness 0.15)
				)
				(justify mirror)
			)
		)
		(property "Val" "2M"
			(at 0 0 180)
			(unlocked yes)
			(layer "B.Fab")
			(hide yes)
			(effects
				(font
					(size 1 1)
					(thickness 0.15)
				)
				(justify mirror)
			)
		)
		(property "Tolerance" "1%"
			(at 0 0 180)
			(unlocked yes)
			(layer "B.Fab")
			(hide yes)
			(effects
				(font
					(size 1 1)
					(thickness 0.15)
				)
				(justify mirror)
			)
		)
		(sheetname "/USB DP Alt mode/")
		(sheetfile "usb_dp.kicad_sch")
		(attr smd)
		(fp_rect
			(start -0.925 0.47)
			(end 0.925 -0.47)
			(stroke
				(width 0.05)
				(type default)
			)
			(fill no)
			(layer "B.CrtYd")
		)
		(fp_rect
			(start -0.5 0.25)
			(end 0.5 -0.25)
			(stroke
				(width 0.15)
				(type solid)
			)
			(fill no)
			(layer "B.Fab")
		)
		(fp_text user "Author: Antmicro"
			(at -0.95 -4.169 0)
			(layer "B.Fab")
			(effects
				(font
					(size 0.7 0.7)
					(thickness 0.15)
				)
				(justify right top mirror)
			)
		)
		(fp_text user "License: Apache-2.0"
			(at -0.95 -5.169 0)
			(layer "B.Fab")
			(effects
				(font
					(size 0.7 0.7)
					(thickness 0.15)
				)
				(justify right top mirror)
			)
		)
		(fp_text user "${REFERENCE}"
			(at -0.95 -3.168 0)
			(layer "B.Fab")
			(effects
				(font
					(size 0.7 0.7)
					(thickness 0.15)
				)
				(justify right top mirror)
			)
		)
		(pad "1" smd roundrect
			(at -0.48 0)
			(size 0.59 0.64)
			(layers "B.Cu" "B.Mask" "B.Paste")
			(roundrect_rratio 0.25)
			(net 815 "/USB DP Alt mode/USBC1_SBU_P")
			(pintype "passive")
		)
		(pad "2" smd roundrect
			(at 0.48 0)
			(size 0.59 0.64)
			(layers "B.Cu" "B.Mask" "B.Paste")
			(roundrect_rratio 0.25)
			(net 1 "GND")
			(pintype "passive")
		)
	)
	(footprint "antmicro-footprints:TP_SMD_0.75mm"
		(layer "B.Cu")
		(at 90.254 60.45 180)
		(property "Reference" "TP118"
			(at -0.346 -0.35 90)
			(layer "B.SilkS")
			(effects
				(font
					(size 0.7 0.7)
					(thickness 0.15)
				)
				(justify left bottom mirror)
			)
		)
		(property "Value" "TP_0.75mm_SMD"
			(at 0 -1.2 0)
			(layer "B.Fab")
			(effects
				(font
					(size 0.7 0.7)
					(thickness 0.15)
				)
				(justify left bottom mirror)
			)
		)
		(property "Description" "SMT test point"
			(at 0 0 0)
			(layer "B.Fab")
			(hide yes)
			(effects
				(font
					(size 1.27 1.27)
					(thickness 0.15)
				)
				(justify mirror)
			)
		)
		(property "MPN" ""
			(at 0 0 0)
			(unlocked yes)
			(layer "B.Fab")
			(hide yes)
			(effects
				(font
					(size 1 1)
					(thickness 0.15)
				)
				(justify mirror)
			)
		)
		(property "Manufacturer" ""
			(at 0 0 0)
			(unlocked yes)
			(layer "B.Fab")
			(hide yes)
			(effects
				(font
					(size 1 1)
					(thickness 0.15)
				)
				(justify mirror)
			)
		)
		(property "Author" "Antmicro"
			(at 0 0 0)
			(unlocked yes)
			(layer "B.Fab")
			(hide yes)
			(effects
				(font
					(size 1 1)
					(thickness 0.15)
				)
				(justify mirror)
			)
		)
		(property "License" "Apache-2.0"
			(at 0 0 0)
			(unlocked yes)
			(layer "B.Fab")
			(hide yes)
			(effects
				(font
					(size 1 1)
					(thickness 0.15)
				)
				(justify mirror)
			)
		)
		(sheetname "/SoM_Power/")
		(sheetfile "som_power.kicad_sch")
		(attr exclude_from_pos_files exclude_from_bom)
		(fp_circle
			(center 0 0)
			(end 0.475 0)
			(stroke
				(width 0.05)
				(type default)
			)
			(fill no)
			(layer "B.CrtYd")
		)
		(fp_text user "${REFERENCE}"
			(at -0.4 -2.7 0)
			(layer "B.Fab")
			(effects
				(font
					(size 0.7 0.7)
					(thickness 0.15)
				)
				(justify left bottom mirror)
			)
		)
		(fp_text user "Author: Antmicro"
			(at -0.4 -3.901 0)
			(layer "B.Fab")
			(effects
				(font
					(size 0.7 0.7)
					(thickness 0.15)
				)
				(justify left bottom mirror)
			)
		)
		(fp_text user "License: Apache-2.0"
			(at -0.4 -5.101 0)
			(layer "B.Fab")
			(effects
				(font
					(size 0.7 0.7)
					(thickness 0.15)
				)
				(justify left bottom mirror)
			)
		)
		(pad "1" smd circle
			(at 0 0 180)
			(size 0.75 0.75)
			(layers "B.Cu" "B.Mask")
			(net 1037 "Net-(U72-~{MR})")
			(pinfunction "1")
			(pintype "passive")
		)
	)
	(footprint "antmicro-footprints:R_0402_1005Metric"
		(layer "B.Cu")
		(at 66.4 65.7 -90)
		(descr "Resistor SMD 0402")
		(tags "resistor SMD 0402")
		(property "Reference" "R392"
			(at 0.9 -0.5 90)
			(layer "B.SilkS")
			(effects
				(font
					(size 0.7 0.7)
					(thickness 0.15)
				)
				(justify left bottom mirror)
			)
		)
		(property "Value" "R_2k2_0402"
			(at -1.011843 -1.772047 90)
			(layer "B.Fab")
			(effects
				(font
					(size 0.7 0.7)
					(thickness 0.15)
				)
				(justify left bottom mirror)
			)
		)
		(property "Datasheet" "https://www.bourns.com/docs/product-datasheets/cr.pdf"
			(at 0 0 90)
			(layer "B.Fab")
			(hide yes)
			(effects
				(font
					(size 1.27 1.27)
					(thickness 0.15)
				)
				(justify mirror)
			)
		)
		(property "Description" "SMD Chip Resistor, 2.2 kohm, ± 1%, 62.5 mW, 0402 [1005 Metric], Thick Film, General Purpose"
			(at 0 0 90)
			(layer "B.Fab")
			(hide yes)
			(effects
				(font
					(size 1.27 1.27)
					(thickness 0.15)
				)
				(justify mirror)
			)
		)
		(property "MPN" "CR0402-FX-2201GLF"
			(at 0 0 90)
			(unlocked yes)
			(layer "B.Fab")
			(hide yes)
			(effects
				(font
					(size 1 1)
					(thickness 0.15)
				)
				(justify mirror)
			)
		)
		(property "Manufacturer" "Bourns"
			(at 0 0 90)
			(unlocked yes)
			(layer "B.Fab")
			(hide yes)
			(effects
				(font
					(size 1 1)
					(thickness 0.15)
				)
				(justify mirror)
			)
		)
		(property "License" "Apache-2.0"
			(at 0 0 90)
			(unlocked yes)
			(layer "B.Fab")
			(hide yes)
			(effects
				(font
					(size 1 1)
					(thickness 0.15)
				)
				(justify mirror)
			)
		)
		(property "Author" "Antmicro"
			(at 0 0 90)
			(unlocked yes)
			(layer "B.Fab")
			(hide yes)
			(effects
				(font
					(size 1 1)
					(thickness 0.15)
				)
				(justify mirror)
			)
		)
		(property "Val" "2k2"
			(at 0 0 90)
			(unlocked yes)
			(layer "B.Fab")
			(hide yes)
			(effects
				(font
					(size 1 1)
					(thickness 0.15)
				)
				(justify mirror)
			)
		)
		(property "Tolerance" "1%"
			(at 0 0 90)
			(unlocked yes)
			(layer "B.Fab")
			(hide yes)
			(effects
				(font
					(size 1 1)
					(thickness 0.15)
				)
				(justify mirror)
			)
		)
		(sheetname "/CSI/")
		(sheetfile "csi.kicad_sch")
		(attr smd)
		(fp_rect
			(start -0.925 0.47)
			(end 0.925 -0.47)
			(stroke
				(width 0.05)
				(type default)
			)
			(fill no)
			(layer "B.CrtYd")
		)
		(fp_rect
			(start -0.5 0.25)
			(end 0.5 -0.25)
			(stroke
				(width 0.15)
				(type solid)
			)
			(fill no)
			(layer "B.Fab")
		)
		(fp_text user "Author: Antmicro"
			(at -0.95 -4.169 90)
			(layer "B.Fab")
			(effects
				(font
					(size 0.7 0.7)
					(thickness 0.15)
				)
				(justify left bottom mirror)
			)
		)
		(fp_text user "${REFERENCE}"
			(at -0.95 -3.168 90)
			(layer "B.Fab")
			(effects
				(font
					(size 0.7 0.7)
					(thickness 0.15)
				)
				(justify left bottom mirror)
			)
		)
		(fp_text user "License: Apache-2.0"
			(at -0.95 -5.169 90)
			(layer "B.Fab")
			(effects
				(font
					(size 0.7 0.7)
					(thickness 0.15)
				)
				(justify left bottom mirror)
			)
		)
		(pad "1" smd roundrect
			(at -0.48 0 270)
			(size 0.59 0.64)
			(layers "B.Cu" "B.Mask" "B.Paste")
			(roundrect_rratio 0.25)
			(net 990 "/CSI/CSIB_I2C_VCC")
			(pintype "passive")
		)
		(pad "2" smd roundrect
			(at 0.48 0 270)
			(size 0.59 0.64)
			(layers "B.Cu" "B.Mask" "B.Paste")
			(roundrect_rratio 0.25)
			(net 994 "/CSI/SCL_CAM2")
			(pintype "passive")
		)
	)
	(footprint "antmicro-footprints:R_0402_1005Metric"
		(layer "B.Cu")
		(at 238.895 61.495 90)
		(descr "Resistor SMD 0402")
		(tags "resistor SMD 0402")
		(property "Reference" "R412"
			(at 1.295 -0.395 90)
			(layer "B.SilkS")
			(effects
				(font
					(size 0.7 0.7)
					(thickness 0.15)
				)
				(justify right top mirror)
			)
		)
		(property "Value" "R_2k2_0402"
			(at -1.011843 -1.772046 90)
			(layer "B.Fab")
			(effects
				(font
					(size 0.7 0.7)
					(thickness 0.15)
				)
				(justify right top mirror)
			)
		)
		(property "Datasheet" "https://www.bourns.com/docs/product-datasheets/cr.pdf"
			(at 0 0 90)
			(layer "B.Fab")
			(hide yes)
			(effects
				(font
					(size 1.27 1.27)
					(thickness 0.15)
				)
				(justify mirror)
			)
		)
		(property "Description" "SMD Chip Resistor, 2.2 kohm, ± 1%, 62.5 mW, 0402 [1005 Metric], Thick Film, General Purpose"
			(at 0 0 90)
			(layer "B.Fab")
			(hide yes)
			(effects
				(font
					(size 1.27 1.27)
					(thickness 0.15)
				)
				(justify mirror)
			)
		)
		(property "MPN" "CR0402-FX-2201GLF"
			(at 0 0 270)
			(unlocked yes)
			(layer "B.Fab")
			(hide yes)
			(effects
				(font
					(size 1 1)
					(thickness 0.15)
				)
				(justify mirror)
			)
		)
		(property "Manufacturer" "Bourns"
			(at 0 0 270)
			(unlocked yes)
			(layer "B.Fab")
			(hide yes)
			(effects
				(font
					(size 1 1)
					(thickness 0.15)
				)
				(justify mirror)
			)
		)
		(property "License" "Apache-2.0"
			(at 0 0 270)
			(unlocked yes)
			(layer "B.Fab")
			(hide yes)
			(effects
				(font
					(size 1 1)
					(thickness 0.15)
				)
				(justify mirror)
			)
		)
		(property "Author" "Antmicro"
			(at 0 0 270)
			(unlocked yes)
			(layer "B.Fab")
			(hide yes)
			(effects
				(font
					(size 1 1)
					(thickness 0.15)
				)
				(justify mirror)
			)
		)
		(property "Val" "2k2"
			(at 0 0 270)
			(unlocked yes)
			(layer "B.Fab")
			(hide yes)
			(effects
				(font
					(size 1 1)
					(thickness 0.15)
				)
				(justify mirror)
			)
		)
		(property "Tolerance" "1%"
			(at 0 0 270)
			(unlocked yes)
			(layer "B.Fab")
			(hide yes)
			(effects
				(font
					(size 1 1)
					(thickness 0.15)
				)
				(justify mirror)
			)
		)
		(sheetname "/Power/")
		(sheetfile "power.kicad_sch")
		(attr smd)
		(fp_poly
			(pts
				(xy -0.925 0.47) (xy 0.925 0.47) (xy 0.925 -0.47) (xy -0.925 -0.47)
			)
			(stroke
				(width 0.05)
				(type default)
			)
			(fill no)
			(layer "B.CrtYd")
		)
		(fp_poly
			(pts
				(xy -0.5 0.25) (xy 0.5 0.25) (xy 0.5 -0.25) (xy -0.5 -0.25)
			)
			(stroke
				(width 0.15)
				(type solid)
			)
			(fill no)
			(layer "B.Fab")
		)
		(fp_text user "Author: Antmicro"
			(at -0.95 -4.169 90)
			(layer "B.Fab")
			(effects
				(font
					(size 0.7 0.7)
					(thickness 0.15)
				)
				(justify right top mirror)
			)
		)
		(fp_text user "License: Apache-2.0"
			(at -0.949999 -5.169 90)
			(layer "B.Fab")
			(effects
				(font
					(size 0.7 0.7)
					(thickness 0.15)
				)
				(justify right top mirror)
			)
		)
		(fp_text user "${REFERENCE}"
			(at -0.95 -3.168 90)
			(layer "B.Fab")
			(effects
				(font
					(size 0.7 0.7)
					(thickness 0.15)
				)
				(justify right top mirror)
			)
		)
		(pad "1" smd roundrect
			(at -0.48 0 90)
			(size 0.59 0.64)
			(layers "B.Cu" "B.Mask" "B.Paste")
			(roundrect_rratio 0.25)
			(net 1395 "Net-(D53-A)")
			(pintype "passive")
		)
		(pad "2" smd roundrect
			(at 0.48 0 90)
			(size 0.59 0.64)
			(layers "B.Cu" "B.Mask" "B.Paste")
			(roundrect_rratio 0.25)
			(net 13 "VCC")
			(pintype "passive")
		)
	)
	(footprint "antmicro-footprints:TP_SMD_0.75mm"
		(layer "B.Cu")
		(at 176.38 58 180)
		(property "Reference" "TP130"
			(at -0.44 4.04 270)
			(layer "B.SilkS")
			(effects
				(font
					(size 0.7 0.7)
					(thickness 0.15)
				)
				(justify left bottom mirror)
			)
		)
		(property "Value" "TP_0.75mm_SMD"
			(at 0 -1.2 0)
			(layer "B.Fab")
			(effects
				(font
					(size 0.7 0.7)
					(thickness 0.15)
				)
				(justify left bottom mirror)
			)
		)
		(property "Description" "SMT test point"
			(at 0 0 0)
			(layer "B.Fab")
			(hide yes)
			(effects
				(font
					(size 1.27 1.27)
					(thickness 0.15)
				)
				(justify mirror)
			)
		)
		(property "MPN" ""
			(at 0 0 0)
			(unlocked yes)
			(layer "B.Fab")
			(hide yes)
			(effects
				(font
					(size 1 1)
					(thickness 0.15)
				)
				(justify mirror)
			)
		)
		(property "Manufacturer" ""
			(at 0 0 0)
			(unlocked yes)
			(layer "B.Fab")
			(hide yes)
			(effects
				(font
					(size 1 1)
					(thickness 0.15)
				)
				(justify mirror)
			)
		)
		(property "Author" "Antmicro"
			(at 0 0 0)
			(unlocked yes)
			(layer "B.Fab")
			(hide yes)
			(effects
				(font
					(size 1 1)
					(thickness 0.15)
				)
				(justify mirror)
			)
		)
		(property "License" "Apache-2.0"
			(at 0 0 0)
			(unlocked yes)
			(layer "B.Fab")
			(hide yes)
			(effects
				(font
					(size 1 1)
					(thickness 0.15)
				)
				(justify mirror)
			)
		)
		(sheetname "/Power/")
		(sheetfile "power.kicad_sch")
		(attr exclude_from_pos_files exclude_from_bom)
		(fp_circle
			(center 0 0)
			(end 0.475 0)
			(stroke
				(width 0.05)
				(type default)
			)
			(fill no)
			(layer "B.CrtYd")
		)
		(fp_text user "Author: Antmicro"
			(at -0.4 -3.901 0)
			(layer "B.Fab")
			(effects
				(font
					(size 0.7 0.7)
					(thickness 0.15)
				)
				(justify left bottom mirror)
			)
		)
		(fp_text user "License: Apache-2.0"
			(at -0.4 -5.101 0)
			(layer "B.Fab")
			(effects
				(font
					(size 0.7 0.7)
					(thickness 0.15)
				)
				(justify left bottom mirror)
			)
		)
		(fp_text user "${REFERENCE}"
			(at -0.4 -2.7 0)
			(layer "B.Fab")
			(effects
				(font
					(size 0.7 0.7)
					(thickness 0.15)
				)
				(justify left bottom mirror)
			)
		)
		(pad "1" smd circle
			(at 0 0 180)
			(size 0.75 0.75)
			(layers "B.Cu" "B.Mask")
			(net 213 "+5V_SOM")
			(pinfunction "1")
			(pintype "passive")
		)
	)
)
